(kicad_pcb
	(version 20260206)
	(generator "pcbnew")
	(generator_version "10.0")
	(general
		(thickness 1.6)
		(legacy_teardrops no)
	)
	(paper "A4")
	(title_block
		(title "baseboard — 13948-1b.1110WZS1818.brd")
		(comment 1 "Honey Badger (Wiwynn) / footprints 2104-2113 of 2523")
	)
	(layers
		(0 "F.Cu" signal "TOP")
		(4 "In1.Cu" signal "L2GND")
		(6 "In2.Cu" signal "L3")
		(8 "In3.Cu" signal "L4VCC")
		(10 "In4.Cu" signal "L5VCC")
		(12 "In5.Cu" signal "L6")
		(14 "In6.Cu" signal "L7GND")
		(2 "B.Cu" signal "BOTTOM")
		(9 "F.Adhes" user "F.Adhesive")
		(11 "B.Adhes" user "B.Adhesive")
		(13 "F.Paste" user "Package Geometry/Pastemask Top")
		(15 "B.Paste" user "Package Geometry/Pastemask Bottom")
		(5 "F.SilkS" user "Ref Des/Silkscreen Top")
		(7 "B.SilkS" user "Ref Des/Silkscreen Bottom")
		(1 "F.Mask" user "Board Geometry/Soldermask Top")
		(3 "B.Mask" user "Board Geometry/Soldermask Bottom")
		(17 "Dwgs.User" user "User.Drawings")
		(19 "Cmts.User" user "User.Comments")
		(21 "Eco1.User" user "User.Eco1")
		(23 "Eco2.User" user "User.Eco2")
		(25 "Edge.Cuts" user "Board Geometry/Outline")
		(27 "Margin" user)
		(31 "F.CrtYd" user "Package Geometry/Place Bound Top")
		(29 "B.CrtYd" user "Package Geometry/Place Bound Bottom")
		(35 "F.Fab" user "Ref Des/Assembly Top")
		(33 "B.Fab" user "Ref Des/Assembly Bottom")
	)
	(footprint ""
		(layer "B.Cu")
		(at 123.298966 -43.815 90)
		(property "Reference" "SC975"
			(at 0 0 90)
			(layer "B.SilkS")
			(hide yes)
			(effects
				(font
					(size 1.27 1.27)
				)
				(justify mirror)
			)
		)
		(property "Value" "SCD1U16V2KX-3GP"
			(at -1.1811 -2.7051 90)
			(unlocked yes)
			(layer "B.Fab")
			(hide yes)
			(effects
				(font
					(size 1.016 1.016)
					(thickness 0.1524)
				)
				(justify mirror)
			)
		)
		(property "Device Type" "C402H22"
			(at -1.1811 -4.2291 90)
			(unlocked yes)
			(layer "B.Fab")
			(hide yes)
			(effects
				(font
					(size 1.016 1.016)
					(thickness 0.1524)
				)
				(justify mirror)
			)
		)
		(duplicate_pad_numbers_are_jumpers no)
		(fp_rect
			(start 0.4318 0.9525)
			(end -0.4318 -0.9525)
			(stroke
				(width 0)
				(type default)
			)
			(fill no)
			(layer "B.CrtYd")
		)
		(fp_rect
			(start 0.4318 0.9525)
			(end -0.4318 -0.9525)
			(stroke
				(width 0)
				(type default)
			)
			(fill no)
			(layer "B.Fab")
		)
		(pad "1" smd custom
			(at 0 -0.4445 270)
			(size 0.1524 0.1524)
			(layers "B.Cu" "B.Mask" "B.Paste")
			(net "P1V8_C")
			(options
				(clearance outline)
				(anchor circle)
			)
			(primitives
				(gr_poly
					(pts
						(arc
							(start 0.3048 0.2032)
							(mid 0.275042 0.275042)
							(end 0.2032 0.3048)
						)
						(arc
							(start -0.2032 0.3048)
							(mid -0.275042 0.275042)
							(end -0.3048 0.2032)
						)
						(arc
							(start -0.3048 -0.2032)
							(mid -0.275042 -0.275042)
							(end -0.2032 -0.3048)
						)
						(arc
							(start 0.2032 -0.3048)
							(mid 0.275042 -0.275042)
							(end 0.3048 -0.2032)
						)
					)
					(width 0)
					(fill yes)
				)
			)
		)
		(pad "2" smd custom
			(at 0 0.4445 270)
			(size 0.1524 0.1524)
			(layers "B.Cu" "B.Mask" "B.Paste")
			(net "GND")
			(options
				(clearance outline)
				(anchor circle)
			)
			(primitives
				(gr_poly
					(pts
						(arc
							(start 0.3048 0.2032)
							(mid 0.275042 0.275042)
							(end 0.2032 0.3048)
						)
						(arc
							(start -0.2032 0.3048)
							(mid -0.275042 0.275042)
							(end -0.3048 0.2032)
						)
						(arc
							(start -0.3048 -0.2032)
							(mid -0.275042 -0.275042)
							(end -0.2032 -0.3048)
						)
						(arc
							(start 0.2032 -0.3048)
							(mid 0.275042 -0.275042)
							(end 0.3048 -0.2032)
						)
					)
					(width 0)
					(fill yes)
				)
			)
		)
	)
	(footprint ""
		(layer "B.Cu")
		(at 82.804 -18.161 180)
		(property "Reference" "PC216"
			(at 0 0 0)
			(layer "B.SilkS")
			(hide yes)
			(effects
				(font
					(size 1.27 1.27)
				)
				(justify mirror)
			)
		)
		(property "Value" "SC22U25V5MX-GP"
			(at 0.0762 -6.1214 180)
			(unlocked yes)
			(layer "B.Fab")
			(hide yes)
			(effects
				(font
					(size 1.016 1.016)
					(thickness 0.1524)
				)
				(justify mirror)
			)
		)
		(property "Device Type" "C805H58"
			(at 0.0762 -8.1534 180)
			(unlocked yes)
			(layer "B.Fab")
			(hide yes)
			(effects
				(font
					(size 1.016 1.016)
					(thickness 0.1524)
				)
				(justify mirror)
			)
		)
		(duplicate_pad_numbers_are_jumpers no)
		(fp_line
			(start -0.635 0)
			(end 0.635 0)
			(stroke
				(width 0.508)
				(type default)
			)
			(layer "B.SilkS")
		)
		(fp_rect
			(start 0.9652 1.778)
			(end -0.9652 -1.778)
			(stroke
				(width 0)
				(type default)
			)
			(fill no)
			(layer "B.CrtYd")
		)
		(fp_poly
			(pts
				(xy 0.9652 -1.778) (xy -0.9652 -1.778) (xy -0.9652 1.778) (xy 0.9652 1.778)
			)
			(stroke
				(width 0)
				(type default)
			)
			(fill no)
			(layer "B.Fab")
		)
		(pad "1" smd rect
			(at 0 -0.9652)
			(size 1.397 1.143)
			(layers "B.Cu" "B.Mask" "B.Paste")
			(net "VT235_VDDL")
		)
		(pad "2" smd rect
			(at 0 0.9652)
			(size 1.397 1.143)
			(layers "B.Cu" "B.Mask" "B.Paste")
			(net "AGND_P0V9_C")
		)
	)
	(footprint ""
		(layer "B.Cu")
		(at 14.48308 -231.822752)
		(property "Reference" "R515"
			(at 0 0 0)
			(layer "B.SilkS")
			(hide yes)
			(effects
				(font
					(size 1.27 1.27)
				)
				(justify mirror)
			)
		)
		(property "Value" "0R2J-2-GP"
			(at -0.064008 -3.993896 0)
			(unlocked yes)
			(layer "B.Fab")
			(hide yes)
			(effects
				(font
					(size 1.016 1.016)
					(thickness 0.1524)
				)
				(justify mirror)
			)
		)
		(property "Device Type" "R402H16"
			(at -0.064008 -5.517896 0)
			(unlocked yes)
			(layer "B.Fab")
			(hide yes)
			(effects
				(font
					(size 1.016 1.016)
					(thickness 0.1524)
				)
				(justify mirror)
			)
		)
		(duplicate_pad_numbers_are_jumpers no)
		(fp_line
			(start -0.508 -0.9398)
			(end 0.508 -0.9398)
			(stroke
				(width 0.1524)
				(type default)
			)
			(layer "B.SilkS")
		)
		(fp_line
			(start 0.508 -0.9398)
			(end 0.508 0.9398)
			(stroke
				(width 0.1524)
				(type default)
			)
			(layer "B.SilkS")
		)
		(fp_rect
			(start 0.508 0.9398)
			(end -0.508 -0.9398)
			(stroke
				(width 0)
				(type default)
			)
			(fill no)
			(layer "B.CrtYd")
		)
		(fp_rect
			(start 0.508 0.9398)
			(end -0.508 -0.9398)
			(stroke
				(width 0)
				(type default)
			)
			(fill no)
			(layer "B.Fab")
		)
		(pad "1" smd custom
			(at 0 -0.4445 180)
			(size 0.1397 0.1397)
			(layers "B.Cu" "B.Mask" "B.Paste")
			(net "SAS_HDD_PWR13_PCIE")
			(options
				(clearance outline)
				(anchor circle)
			)
			(primitives
				(gr_poly
					(pts
						(arc
							(start -0.1778 0.2794)
							(mid -0.249642 0.249642)
							(end -0.2794 0.1778)
						)
						(arc
							(start -0.2794 -0.1778)
							(mid -0.249642 -0.249642)
							(end -0.1778 -0.2794)
						)
						(arc
							(start 0.1778 -0.2794)
							(mid 0.249642 -0.249642)
							(end 0.2794 -0.1778)
						)
						(arc
							(start 0.2794 0.1778)
							(mid 0.249642 0.249642)
							(end 0.1778 0.2794)
						)
					)
					(width 0)
					(fill yes)
				)
			)
		)
		(pad "2" smd custom
			(at 0 0.4445 180)
			(size 0.1397 0.1397)
			(layers "B.Cu" "B.Mask" "B.Paste")
			(net "SAS_HDD_PWR13")
			(options
				(clearance outline)
				(anchor circle)
			)
			(primitives
				(gr_poly
					(pts
						(arc
							(start -0.1778 0.2794)
							(mid -0.249642 0.249642)
							(end -0.2794 0.1778)
						)
						(arc
							(start -0.2794 -0.1778)
							(mid -0.249642 -0.249642)
							(end -0.1778 -0.2794)
						)
						(arc
							(start 0.1778 -0.2794)
							(mid 0.249642 -0.249642)
							(end 0.2794 -0.1778)
						)
						(arc
							(start 0.2794 0.1778)
							(mid 0.249642 0.249642)
							(end 0.1778 0.2794)
						)
					)
					(width 0)
					(fill yes)
				)
			)
		)
	)
	(footprint ""
		(layer "B.Cu")
		(at 298.0944 -178.943)
		(property "Reference" "TP89"
			(at 0 0 0)
			(layer "B.SilkS")
			(hide yes)
			(effects
				(font
					(size 1.27 1.27)
				)
				(justify mirror)
			)
		)
		(property "Value" "TPAD28"
			(at -0.0127 -1.8034 0)
			(unlocked yes)
			(layer "B.Fab")
			(hide yes)
			(effects
				(font
					(size 1.016 1.016)
					(thickness 0.1524)
				)
				(justify mirror)
			)
		)
		(property "Device Type" "TPAD28"
			(at -0.0127 -3.3274 0)
			(unlocked yes)
			(layer "B.Fab")
			(hide yes)
			(effects
				(font
					(size 1.016 1.016)
					(thickness 0.1524)
				)
				(justify mirror)
			)
		)
		(duplicate_pad_numbers_are_jumpers no)
		(fp_poly
			(pts
				(arc
					(start 0.3556 0)
					(mid -0.3556 0)
					(end 0.3556 0)
				)
			)
			(stroke
				(width 0)
				(type default)
			)
			(fill no)
			(layer "B.CrtYd")
		)
		(fp_poly
			(pts
				(arc
					(start 0.6096 0)
					(mid -0.6096 0)
					(end 0.6096 0)
				)
			)
			(stroke
				(width 0)
				(type default)
			)
			(fill no)
			(layer "B.Fab")
		)
		(pad "1" smd circle
			(at 0 0 180)
			(size 0.7112 0.7112)
			(layers "B.Cu" "B.Mask" "B.Paste")
			(net "TP_BMC_GPIOL1")
		)
	)
	(footprint ""
		(layer "B.Cu")
		(at 99.189286 -37.69868 -90)
		(property "Reference" "SC941"
			(at 0 0 90)
			(layer "B.SilkS")
			(hide yes)
			(effects
				(font
					(size 1.27 1.27)
				)
				(justify mirror)
			)
		)
		(property "Value" "SC1U6D3V1MX-GP"
			(at -1.9177 2.0193 270)
			(unlocked yes)
			(layer "B.Fab")
			(hide yes)
			(effects
				(font
					(size 1.016 1.016)
					(thickness 0.1524)
				)
				(justify mirror)
			)
		)
		(property "Device Type" "C0201H14"
			(at -1.9177 0.4953 270)
			(unlocked yes)
			(layer "B.Fab")
			(hide yes)
			(effects
				(font
					(size 1.016 1.016)
					(thickness 0.1524)
				)
				(justify mirror)
			)
		)
		(duplicate_pad_numbers_are_jumpers no)
		(fp_rect
			(start 0.1524 0.3048)
			(end -0.1524 -0.3048)
			(stroke
				(width 0)
				(type default)
			)
			(fill no)
			(layer "B.CrtYd")
		)
		(fp_poly
			(pts
				(xy 0.2794 0.6477) (xy 0.2794 -0.6477) (xy -0.2794 -0.6477) (xy -0.2794 -0.1905) (xy -0.1524 -0.1905)
				(xy -0.1524 -0.3048) (xy 0.1524 -0.3048) (xy 0.1524 0.3048) (xy -0.1524 0.3048) (xy -0.1524 -0.1778)
				(xy -0.2794 -0.1778) (xy -0.2794 0.6477)
			)
			(stroke
				(width 0)
				(type default)
			)
			(fill no)
			(layer "B.CrtYd")
		)
		(fp_rect
			(start 0.2794 0.6477)
			(end -0.2794 -0.6477)
			(stroke
				(width 0)
				(type default)
			)
			(fill no)
			(layer "B.Fab")
		)
		(pad "1" smd custom
			(at 0 -0.2794 90)
			(size 0.0762 0.0762)
			(layers "B.Cu" "B.Mask" "B.Paste")
			(net "P1V5_C")
			(options
				(clearance outline)
				(anchor circle)
			)
			(primitives
				(gr_poly
					(pts
						(arc
							(start 0.1524 0.127)
							(mid 0.137521 0.162921)
							(end 0.1016 0.1778)
						)
						(arc
							(start -0.1016 0.1778)
							(mid -0.137521 0.162921)
							(end -0.1524 0.127)
						)
						(arc
							(start -0.1524 -0.127)
							(mid -0.137521 -0.162921)
							(end -0.1016 -0.1778)
						)
						(arc
							(start 0.1016 -0.1778)
							(mid 0.137521 -0.162921)
							(end 0.1524 -0.127)
						)
					)
					(width 0)
					(fill yes)
				)
			)
		)
		(pad "2" smd custom
			(at 0 0.2794 90)
			(size 0.0762 0.0762)
			(layers "B.Cu" "B.Mask" "B.Paste")
			(net "GND")
			(options
				(clearance outline)
				(anchor circle)
			)
			(primitives
				(gr_poly
					(pts
						(arc
							(start 0.1524 0.127)
							(mid 0.137521 0.162921)
							(end 0.1016 0.1778)
						)
						(arc
							(start -0.1016 0.1778)
							(mid -0.137521 0.162921)
							(end -0.1524 0.127)
						)
						(arc
							(start -0.1524 -0.127)
							(mid -0.137521 -0.162921)
							(end -0.1016 -0.1778)
						)
						(arc
							(start 0.1016 -0.1778)
							(mid 0.137521 -0.162921)
							(end 0.1524 -0.127)
						)
					)
					(width 0)
					(fill yes)
				)
			)
		)
	)
	(footprint ""
		(layer "B.Cu")
		(at 124.403612 -214.376 90)
		(property "Reference" "SR904"
			(at 0 0 90)
			(layer "B.SilkS")
			(hide yes)
			(effects
				(font
					(size 1.27 1.27)
				)
				(justify mirror)
			)
		)
		(property "Value" "4K7R2F-GP"
			(at -0.064008 -3.993896 90)
			(unlocked yes)
			(layer "B.Fab")
			(hide yes)
			(effects
				(font
					(size 1.016 1.016)
					(thickness 0.1524)
				)
				(justify mirror)
			)
		)
		(property "Device Type" "R402H16"
			(at -0.064008 -5.517896 90)
			(unlocked yes)
			(layer "B.Fab")
			(hide yes)
			(effects
				(font
					(size 1.016 1.016)
					(thickness 0.1524)
				)
				(justify mirror)
			)
		)
		(duplicate_pad_numbers_are_jumpers no)
		(fp_line
			(start 0.508 -0.9398)
			(end 0.508 0.9398)
			(stroke
				(width 0.1524)
				(type default)
			)
			(layer "B.SilkS")
		)
		(fp_line
			(start -0.508 -0.9398)
			(end 0.508 -0.9398)
			(stroke
				(width 0.1524)
				(type default)
			)
			(layer "B.SilkS")
		)
		(fp_rect
			(start 0.508 0.9398)
			(end -0.508 -0.9398)
			(stroke
				(width 0)
				(type default)
			)
			(fill no)
			(layer "B.CrtYd")
		)
		(fp_rect
			(start 0.508 0.9398)
			(end -0.508 -0.9398)
			(stroke
				(width 0)
				(type default)
			)
			(fill no)
			(layer "B.Fab")
		)
		(pad "1" smd custom
			(at 0 -0.4445 270)
			(size 0.1397 0.1397)
			(layers "B.Cu" "B.Mask" "B.Paste")
			(net "REDV_D1_A")
			(options
				(clearance outline)
				(anchor circle)
			)
			(primitives
				(gr_poly
					(pts
						(arc
							(start -0.1778 0.2794)
							(mid -0.249642 0.249642)
							(end -0.2794 0.1778)
						)
						(arc
							(start -0.2794 -0.1778)
							(mid -0.249642 -0.249642)
							(end -0.1778 -0.2794)
						)
						(arc
							(start 0.1778 -0.2794)
							(mid 0.249642 -0.249642)
							(end 0.2794 -0.1778)
						)
						(arc
							(start 0.2794 0.1778)
							(mid 0.249642 0.249642)
							(end 0.1778 0.2794)
						)
					)
					(width 0)
					(fill yes)
				)
			)
		)
		(pad "2" smd custom
			(at 0 0.4445 270)
			(size 0.1397 0.1397)
			(layers "B.Cu" "B.Mask" "B.Paste")
			(net "GND")
			(options
				(clearance outline)
				(anchor circle)
			)
			(primitives
				(gr_poly
					(pts
						(arc
							(start -0.1778 0.2794)
							(mid -0.249642 0.249642)
							(end -0.2794 0.1778)
						)
						(arc
							(start -0.2794 -0.1778)
							(mid -0.249642 -0.249642)
							(end -0.1778 -0.2794)
						)
						(arc
							(start 0.1778 -0.2794)
							(mid 0.249642 -0.249642)
							(end 0.2794 -0.1778)
						)
						(arc
							(start 0.2794 0.1778)
							(mid 0.249642 0.249642)
							(end 0.1778 0.2794)
						)
					)
					(width 0)
					(fill yes)
				)
			)
		)
	)
	(footprint ""
		(layer "B.Cu")
		(at 341.507318 -135.385048 -90)
		(property "Reference" "R556"
			(at 0 0 90)
			(layer "B.SilkS")
			(hide yes)
			(effects
				(font
					(size 1.27 1.27)
				)
				(justify mirror)
			)
		)
		(property "Value" "0R3J-0-U-GP"
			(at 0.0254 -2.5146 270)
			(unlocked yes)
			(layer "B.Fab")
			(hide yes)
			(effects
				(font
					(size 1.016 1.016)
					(thickness 0.1524)
				)
				(justify mirror)
			)
		)
		(property "Device Type" "R603H22"
			(at 0.0254 -4.0386 270)
			(unlocked yes)
			(layer "B.Fab")
			(hide yes)
			(effects
				(font
					(size 1.016 1.016)
					(thickness 0.1524)
				)
				(justify mirror)
			)
		)
		(duplicate_pad_numbers_are_jumpers no)
		(fp_line
			(start -0.2032 0)
			(end -0.4826 0)
			(stroke
				(width 0.2032)
				(type default)
			)
			(layer "B.SilkS")
		)
		(fp_line
			(start 0.4826 0)
			(end 0.2032 0)
			(stroke
				(width 0.2032)
				(type default)
			)
			(layer "B.SilkS")
		)
		(fp_rect
			(start 0.5842 1.3335)
			(end -0.5842 -1.3335)
			(stroke
				(width 0)
				(type default)
			)
			(fill no)
			(layer "B.CrtYd")
		)
		(fp_rect
			(start 0.5842 1.3335)
			(end -0.5842 -1.3335)
			(stroke
				(width 0)
				(type default)
			)
			(fill no)
			(layer "B.Fab")
		)
		(pad "1" smd custom
			(at 0 -0.762 90)
			(size 0.2159 0.2159)
			(layers "B.Cu" "B.Mask" "B.Paste")
			(net "USB_P1_DN")
			(options
				(clearance outline)
				(anchor circle)
			)
			(primitives
				(gr_poly
					(pts
						(arc
							(start -0.3302 0.4318)
							(mid -0.402042 0.402042)
							(end -0.4318 0.3302)
						)
						(arc
							(start -0.4318 -0.3302)
							(mid -0.402042 -0.402042)
							(end -0.3302 -0.4318)
						)
						(arc
							(start 0.3302 -0.4318)
							(mid 0.402042 -0.402042)
							(end 0.4318 -0.3302)
						)
						(arc
							(start 0.4318 0.3302)
							(mid 0.402042 0.402042)
							(end 0.3302 0.4318)
						)
					)
					(width 0)
					(fill yes)
				)
			)
		)
		(pad "2" smd custom
			(at 0 0.762 90)
			(size 0.2159 0.2159)
			(layers "B.Cu" "B.Mask" "B.Paste")
			(net "USB_DN_R")
			(options
				(clearance outline)
				(anchor circle)
			)
			(primitives
				(gr_poly
					(pts
						(arc
							(start -0.3302 0.4318)
							(mid -0.402042 0.402042)
							(end -0.4318 0.3302)
						)
						(arc
							(start -0.4318 -0.3302)
							(mid -0.402042 -0.402042)
							(end -0.3302 -0.4318)
						)
						(arc
							(start 0.3302 -0.4318)
							(mid 0.402042 -0.402042)
							(end 0.4318 -0.3302)
						)
						(arc
							(start 0.4318 0.3302)
							(mid 0.402042 0.402042)
							(end 0.3302 0.4318)
						)
					)
					(width 0)
					(fill yes)
				)
			)
		)
	)
	(footprint ""
		(layer "B.Cu")
		(at 46.81093 -77.650086)
		(property "Reference" "TP188"
			(at 0 0 0)
			(layer "B.SilkS")
			(hide yes)
			(effects
				(font
					(size 1.27 1.27)
				)
				(justify mirror)
			)
		)
		(property "Value" "TPAD32-GP"
			(at 0 -3.166364 0)
			(unlocked yes)
			(layer "B.Fab")
			(hide yes)
			(effects
				(font
					(size 1.016 1.016)
					(thickness 0.1524)
				)
				(justify mirror)
			)
		)
		(property "Device Type" "TPAD32"
			(at 0 -4.690618 0)
			(unlocked yes)
			(layer "B.Fab")
			(hide yes)
			(effects
				(font
					(size 1.016 1.016)
					(thickness 0.1524)
				)
				(justify mirror)
			)
		)
		(duplicate_pad_numbers_are_jumpers no)
		(fp_poly
			(pts
				(arc
					(start 0.4064 0)
					(mid -0.4064 0)
					(end 0.4064 0)
				)
			)
			(stroke
				(width 0)
				(type default)
			)
			(fill no)
			(layer "B.CrtYd")
		)
		(fp_poly
			(pts
				(arc
					(start 0.7112 0)
					(mid -0.7112 0)
					(end 0.7112 0)
				)
			)
			(stroke
				(width 0)
				(type default)
			)
			(fill no)
			(layer "B.Fab")
		)
		(pad "1" smd circle
			(at 0 0 180)
			(size 0.8128 0.8128)
			(layers "B.Cu" "B.Mask" "B.Paste")
			(net "INT_CONN_A_SB7")
		)
	)
	(footprint ""
		(layer "B.Cu")
		(at 114.94897 -89.6366)
		(property "Reference" "STP69"
			(at 0 0 0)
			(layer "B.SilkS")
			(hide yes)
			(effects
				(font
					(size 1.27 1.27)
				)
				(justify mirror)
			)
		)
		(property "Value" "TPAD28"
			(at -0.0127 -1.8034 0)
			(unlocked yes)
			(layer "B.Fab")
			(hide yes)
			(effects
				(font
					(size 1.016 1.016)
					(thickness 0.1524)
				)
				(justify mirror)
			)
		)
		(property "Device Type" "TPAD28"
			(at -0.0127 -3.3274 0)
			(unlocked yes)
			(layer "B.Fab")
			(hide yes)
			(effects
				(font
					(size 1.016 1.016)
					(thickness 0.1524)
				)
				(justify mirror)
			)
		)
		(duplicate_pad_numbers_are_jumpers no)
		(fp_poly
			(pts
				(arc
					(start 0.3556 0)
					(mid -0.3556 0)
					(end 0.3556 0)
				)
			)
			(stroke
				(width 0)
				(type default)
			)
			(fill no)
			(layer "B.CrtYd")
		)
		(fp_poly
			(pts
				(arc
					(start 0.6096 0)
					(mid -0.6096 0)
					(end 0.6096 0)
				)
			)
			(stroke
				(width 0)
				(type default)
			)
			(fill no)
			(layer "B.Fab")
		)
		(pad "1" smd circle
			(at 0 0 180)
			(size 0.7112 0.7112)
			(layers "B.Cu" "B.Mask" "B.Paste")
			(net "EXP_TEST_MUX31")
		)
	)
	(footprint ""
		(layer "B.Cu")
		(at 143.9926 -49.7586)
		(property "Reference" "STP120"
			(at 0 0 0)
			(layer "B.SilkS")
			(hide yes)
			(effects
				(font
					(size 1.27 1.27)
				)
				(justify mirror)
			)
		)
		(property "Value" "TPAD28"
			(at -0.0127 -1.8034 0)
			(unlocked yes)
			(layer "B.Fab")
			(hide yes)
			(effects
				(font
					(size 1.016 1.016)
					(thickness 0.1524)
				)
				(justify mirror)
			)
		)
		(property "Device Type" "TPAD28"
			(at -0.0127 -3.3274 0)
			(unlocked yes)
			(layer "B.Fab")
			(hide yes)
			(effects
				(font
					(size 1.016 1.016)
					(thickness 0.1524)
				)
				(justify mirror)
			)
		)
		(duplicate_pad_numbers_are_jumpers no)
		(fp_poly
			(pts
				(arc
					(start 0.3556 0)
					(mid -0.3556 0)
					(end 0.3556 0)
				)
			)
			(stroke
				(width 0)
				(type default)
			)
			(fill no)
			(layer "B.CrtYd")
		)
		(fp_poly
			(pts
				(arc
					(start 0.6096 0)
					(mid -0.6096 0)
					(end 0.6096 0)
				)
			)
			(stroke
				(width 0)
				(type default)
			)
			(fill no)
			(layer "B.Fab")
		)
		(pad "1" smd circle
			(at 0 0 180)
			(size 0.7112 0.7112)
			(layers "B.Cu" "B.Mask" "B.Paste")
			(net "XM_ADDR_20")
		)
	)
)
